(kicad_pcb
	(version 20260206)
	(generator "pcbnew")
	(generator_version "10.0")
	(general
		(thickness 1.6)
		(legacy_teardrops no)
	)
	(paper "A4")
	(title_block
		(title "netronome-mezz — pcbd0082-001_rev01_jul9_a.brd")
		(comment 1 "Open CloudServer (Microsoft) / footprints 157-165 of 714")
	)
	(layers
		(0 "F.Cu" signal "TOP")
		(4 "In1.Cu" signal "02_GND")
		(6 "In2.Cu" signal "03_SIG")
		(8 "In3.Cu" signal "04_SIG")
		(10 "In4.Cu" signal "05_GND")
		(12 "In5.Cu" signal "06_PWR1")
		(14 "In6.Cu" signal "07_SIG")
		(16 "In7.Cu" signal "08_SIG")
		(18 "In8.Cu" signal "09_GND")
		(2 "B.Cu" signal "BOTTOM")
		(9 "F.Adhes" user "F.Adhesive")
		(11 "B.Adhes" user "B.Adhesive")
		(13 "F.Paste" user "Package Geometry/Pastemask Top")
		(15 "B.Paste" user "Package Geometry/Pastemask Bottom")
		(5 "F.SilkS" user "Ref Des/Silkscreen Top")
		(7 "B.SilkS" user "Ref Des/Silkscreen Bottom")
		(1 "F.Mask" user "Board Geometry/Soldermask Top")
		(3 "B.Mask" user "Board Geometry/Soldermask Bottom")
		(17 "Dwgs.User" user "User.Drawings")
		(19 "Cmts.User" user "User.Comments")
		(21 "Eco1.User" user "User.Eco1")
		(23 "Eco2.User" user "User.Eco2")
		(25 "Edge.Cuts" user "Board Geometry/Outline")
		(27 "Margin" user)
		(31 "F.CrtYd" user "Package Geometry/Place Bound Top")
		(29 "B.CrtYd" user "Package Geometry/Place Bound Bottom")
		(35 "F.Fab" user "Ref Des/Assembly Top")
		(33 "B.Fab" user "Ref Des/Assembly Bottom")
		(45 "User.4" user "COMPVAL_TYPE_BOTTOM")
	)
	(footprint ""
		(layer "F.Cu")
		(at 10.16 44.196)
		(property "Reference" "L11"
			(at -2.51333 -0.381 90)
			(unlocked yes)
			(layer "F.SilkS")
			(effects
				(font
					(size 0.7874 0.5842)
					(thickness 0.127)
				)
				(justify left)
			)
		)
		(property "Value" "2.2UH"
			(at -0.483362 -0.148082 0)
			(unlocked yes)
			(layer "F.Fab")
			(hide yes)
			(effects
				(font
					(size 1.27 0.9652)
					(thickness 0.000001)
				)
				(justify left)
			)
		)
		(property "Device Type" "INDS0060"
			(at -0.483362 -0.148082 0)
			(unlocked yes)
			(layer "F.Fab")
			(hide yes)
			(effects
				(font
					(size 1.27 0.9652)
					(thickness 0.000001)
				)
				(justify left)
			)
		)
		(duplicate_pad_numbers_are_jumpers no)
		(fp_line
			(start -1.27 -1.397)
			(end 1.27 -1.397)
			(stroke
				(width 0.1524)
				(type default)
			)
			(layer "F.SilkS")
		)
		(fp_line
			(start 1.27 1.397)
			(end -1.27 1.397)
			(stroke
				(width 0.1524)
				(type default)
			)
			(layer "F.SilkS")
		)
		(fp_poly
			(pts
				(xy 2.159 -1.651) (xy 2.159 1.651) (xy -1.794535 1.651) (xy -1.794535 -1.651)
			)
			(stroke
				(width 0)
				(type default)
			)
			(fill no)
			(layer "F.CrtYd")
		)
		(fp_line
			(start -1.3462 -1.1049)
			(end -1.3462 1.1049)
			(stroke
				(width 0.1524)
				(type default)
			)
			(layer "F.Fab")
		)
		(fp_line
			(start -1.3462 1.1049)
			(end 1.3462 1.1049)
			(stroke
				(width 0.1524)
				(type default)
			)
			(layer "F.Fab")
		)
		(fp_line
			(start 1.3462 -1.1049)
			(end -1.3462 -1.1049)
			(stroke
				(width 0.1524)
				(type default)
			)
			(layer "F.Fab")
		)
		(fp_line
			(start 1.3462 1.1049)
			(end 1.3462 -1.1049)
			(stroke
				(width 0.1524)
				(type default)
			)
			(layer "F.Fab")
		)
		(pad "1" smd rect
			(at -1.1303 0)
			(size 1.1938 2.3368)
			(layers "F.Cu" "F.Mask" "F.Paste")
			(net "VDD_1.5V")
		)
		(pad "2" smd rect
			(at 1.1303 0)
			(size 1.1938 2.3368)
			(layers "F.Cu" "F.Mask" "F.Paste")
			(net "11N1968")
		)
		(zone
			(layer "F.Cu")
			(hatch none 0.5)
			(connect_pads
				(clearance 0)
			)
			(min_thickness 0.25)
			(keepout
				(tracks allowed)
				(vias not_allowed)
				(pads allowed)
				(copperpour not_allowed)
				(footprints allowed)
			)
			(placement
				(enabled no)
				(sheetname "")
			)
			(fill
				(thermal_gap 0.5)
				(thermal_bridge_width 0.5)
				(island_removal_mode 0)
			)
			(polygon
				(pts
					(xy 8.8138 45.3009) (xy 11.5062 45.3009) (xy 11.5062 43.0911) (xy 8.8138 43.0911)
				)
			)
		)
	)
	(footprint ""
		(layer "F.Cu")
		(at 19.304 1.397 -90)
		(property "Reference" "R371"
			(at -0.381 0.22733 90)
			(unlocked yes)
			(layer "F.SilkS")
			(effects
				(font
					(size 0.7874 0.5842)
					(thickness 0.127)
				)
				(justify left)
			)
		)
		(property "Value" "4.75K"
			(at -0.148158 1.3462 0)
			(unlocked yes)
			(layer "F.Fab")
			(hide yes)
			(effects
				(font
					(size 1.27 0.9652)
					(thickness 0.000001)
				)
				(justify left)
			)
		)
		(property "Device Type" "REST4024"
			(at -0.148158 1.3462 0)
			(unlocked yes)
			(layer "F.Fab")
			(hide yes)
			(effects
				(font
					(size 1.27 0.9652)
					(thickness 0.000001)
				)
				(justify left)
			)
		)
		(duplicate_pad_numbers_are_jumpers no)
		(fp_poly
			(pts
				(xy 0.635 1.0668) (xy 0.635 -1.0668) (xy -0.635 -1.0668) (xy -0.635 1.0668)
			)
			(stroke
				(width 0)
				(type default)
			)
			(fill no)
			(layer "F.CrtYd")
		)
		(fp_line
			(start -0.254 0.508)
			(end -0.254 -0.508)
			(stroke
				(width 0.0254)
				(type default)
			)
			(layer "F.Fab")
		)
		(fp_line
			(start 0.254 0.508)
			(end -0.254 0.508)
			(stroke
				(width 0.0254)
				(type default)
			)
			(layer "F.Fab")
		)
		(fp_line
			(start -0.254 -0.508)
			(end 0.254 -0.508)
			(stroke
				(width 0.0254)
				(type default)
			)
			(layer "F.Fab")
		)
		(fp_line
			(start 0.254 -0.508)
			(end 0.254 0.508)
			(stroke
				(width 0.0254)
				(type default)
			)
			(layer "F.Fab")
		)
		(pad "1" smd rect
			(at 0 -0.4191 270)
			(size 0.508 0.5334)
			(layers "F.Cu" "F.Mask" "F.Paste")
			(net "13N4315")
		)
		(pad "2" smd rect
			(at 0 0.4191 270)
			(size 0.508 0.5334)
			(layers "F.Cu" "F.Mask" "F.Paste")
			(net "GND")
		)
		(zone
			(layer "F.Cu")
			(hatch none 0.5)
			(connect_pads
				(clearance 0)
			)
			(min_thickness 0.25)
			(keepout
				(tracks not_allowed)
				(vias allowed)
				(pads allowed)
				(copperpour not_allowed)
				(footprints allowed)
			)
			(placement
				(enabled no)
				(sheetname "")
			)
			(fill
				(thermal_gap 0.5)
				(thermal_bridge_width 0.5)
				(island_removal_mode 0)
			)
			(polygon
				(pts
					(xy 19.3294 1.4224) (xy 19.2786 1.4224) (xy 19.2786 1.3716) (xy 19.3294 1.3716)
				)
			)
		)
	)
	(footprint ""
		(layer "F.Cu")
		(at 53.086 52.0192 -90)
		(property "Reference" "C64"
			(at 1.34747 -0.127 0)
			(unlocked yes)
			(layer "F.SilkS")
			(effects
				(font
					(size 0.7874 0.5842)
					(thickness 0.127)
				)
				(justify left)
			)
		)
		(property "Value" "100UF"
			(at -0.78232 0.4826 0)
			(unlocked yes)
			(layer "F.Fab")
			(hide yes)
			(effects
				(font
					(size 1.27 0.9652)
					(thickness 0.000001)
				)
				(justify left)
			)
		)
		(property "Device Type" "CAPC0087"
			(at -0.78232 0.4826 0)
			(unlocked yes)
			(layer "F.Fab")
			(hide yes)
			(effects
				(font
					(size 1.27 0.9652)
					(thickness 0.000001)
				)
				(justify left)
			)
		)
		(duplicate_pad_numbers_are_jumpers no)
		(fp_circle
			(center 0 0)
			(end 0 -0.508)
			(stroke
				(width 0.2032)
				(type default)
			)
			(fill no)
			(layer "F.SilkS")
		)
		(fp_circle
			(center 0 0)
			(end 0 -0.508)
			(stroke
				(width 0.2032)
				(type default)
			)
			(fill no)
			(layer "F.SilkS")
		)
		(fp_poly
			(pts
				(xy -1.27 2.9464) (xy 1.27 2.9464) (xy 1.27 -2.9464) (xy -1.27 -2.9464)
			)
			(stroke
				(width 0)
				(type default)
			)
			(fill no)
			(layer "F.CrtYd")
		)
		(fp_line
			(start -1.016 2.794)
			(end -1.016 -2.794)
			(stroke
				(width 0.0254)
				(type default)
			)
			(layer "F.Fab")
		)
		(fp_line
			(start 1.016 2.794)
			(end -1.016 2.794)
			(stroke
				(width 0.0254)
				(type default)
			)
			(layer "F.Fab")
		)
		(fp_line
			(start -1.016 -2.794)
			(end 1.016 -2.794)
			(stroke
				(width 0.0254)
				(type default)
			)
			(layer "F.Fab")
		)
		(fp_line
			(start 1.016 -2.794)
			(end 1.016 2.794)
			(stroke
				(width 0.0254)
				(type default)
			)
			(layer "F.Fab")
		)
		(pad "1" smd rect
			(at 0 -1.6764 270)
			(size 1.524 1.524)
			(layers "F.Cu" "F.Mask" "F.Paste")
			(net "VDD_CORE")
		)
		(pad "2" smd rect
			(at 0 1.6764 270)
			(size 1.524 1.524)
			(layers "F.Cu" "F.Mask" "F.Paste")
			(net "GND")
		)
		(zone
			(layer "F.Cu")
			(hatch none 0.5)
			(connect_pads
				(clearance 0)
			)
			(min_thickness 0.25)
			(keepout
				(tracks allowed)
				(vias not_allowed)
				(pads allowed)
				(copperpour not_allowed)
				(footprints allowed)
			)
			(placement
				(enabled no)
				(sheetname "")
			)
			(fill
				(thermal_gap 0.5)
				(thermal_bridge_width 0.5)
				(island_removal_mode 0)
			)
			(polygon
				(pts
					(xy 51.4858 51.2318) (xy 51.4858 52.8066) (xy 54.6862 52.8066) (xy 54.6862 51.2318)
				)
			)
		)
		(zone
			(layer "F.Cu")
			(hatch none 0.5)
			(connect_pads
				(clearance 0)
			)
			(min_thickness 0.25)
			(keepout
				(tracks not_allowed)
				(vias allowed)
				(pads allowed)
				(copperpour not_allowed)
				(footprints allowed)
			)
			(placement
				(enabled no)
				(sheetname "")
			)
			(fill
				(thermal_gap 0.5)
				(thermal_bridge_width 0.5)
				(island_removal_mode 0)
			)
			(polygon
				(pts
					(xy 52.3494 51.2318) (xy 52.3494 52.8066) (xy 52.197 52.8066) (xy 52.197 51.2318)
				)
			)
		)
		(zone
			(layer "F.Cu")
			(hatch none 0.5)
			(connect_pads
				(clearance 0)
			)
			(min_thickness 0.25)
			(keepout
				(tracks not_allowed)
				(vias allowed)
				(pads allowed)
				(copperpour not_allowed)
				(footprints allowed)
			)
			(placement
				(enabled no)
				(sheetname "")
			)
			(fill
				(thermal_gap 0.5)
				(thermal_bridge_width 0.5)
				(island_removal_mode 0)
			)
			(polygon
				(pts
					(xy 53.975 51.2318) (xy 53.975 52.8066) (xy 53.8226 52.8066) (xy 53.8226 51.2318)
				)
			)
		)
	)
	(footprint ""
		(layer "F.Cu")
		(at 77.051002 14.256004)
		(property "Reference" "V_A-DQ19"
			(at 0 0 0)
			(layer "F.SilkS")
			(hide yes)
			(effects
				(font
					(size 1.27 1.27)
				)
			)
		)
		(property "Value" ""
			(at 0 0 0)
			(layer "F.Fab")
			(effects
				(font
					(size 1.27 1.27)
				)
			)
		)
		(duplicate_pad_numbers_are_jumpers no)
		(pad "1" thru_hole circle
			(at 0 0)
			(size 0.762 0.762)
			(drill 0.20574)
			(layers "*.Cu" "*.Mask")
			(remove_unused_layers no)
			(net "DDR0_32A_DQ19")
			(clearance 0.127)
			(thermal_gap 0.127)
			(padstack
				(mode front_inner_back)
				(layer "Inner"
					(shape circle)
					(size 0.4572 0.4572)
					(clearance 0.1143)
				)
				(layer "B.Cu"
					(shape circle)
					(size 0.4572 0.4572)
					(clearance 0.1143)
				)
			)
		)
	)
	(footprint ""
		(layer "F.Cu")
		(at 0.635 34.163)
		(property "Reference" "R103"
			(at 0 0 0)
			(layer "F.SilkS")
			(hide yes)
			(effects
				(font
					(size 1.27 1.27)
				)
			)
		)
		(property "Value" "4.75K"
			(at -0.148158 1.3462 90)
			(unlocked yes)
			(layer "F.Fab")
			(hide yes)
			(effects
				(font
					(size 1.27 0.9652)
					(thickness 0.000001)
				)
				(justify left)
			)
		)
		(property "Device Type" "REST4024"
			(at -0.148158 1.3462 90)
			(unlocked yes)
			(layer "F.Fab")
			(hide yes)
			(effects
				(font
					(size 1.27 0.9652)
					(thickness 0.000001)
				)
				(justify left)
			)
		)
		(duplicate_pad_numbers_are_jumpers no)
		(fp_poly
			(pts
				(xy 0.635 1.0668) (xy 0.635 -1.0668) (xy -0.635 -1.0668) (xy -0.635 1.0668)
			)
			(stroke
				(width 0)
				(type default)
			)
			(fill no)
			(layer "F.CrtYd")
		)
		(fp_line
			(start -0.254 -0.508)
			(end 0.254 -0.508)
			(stroke
				(width 0.0254)
				(type default)
			)
			(layer "F.Fab")
		)
		(fp_line
			(start -0.254 0.508)
			(end -0.254 -0.508)
			(stroke
				(width 0.0254)
				(type default)
			)
			(layer "F.Fab")
		)
		(fp_line
			(start 0.254 -0.508)
			(end 0.254 0.508)
			(stroke
				(width 0.0254)
				(type default)
			)
			(layer "F.Fab")
		)
		(fp_line
			(start 0.254 0.508)
			(end -0.254 0.508)
			(stroke
				(width 0.0254)
				(type default)
			)
			(layer "F.Fab")
		)
		(pad "1" smd rect
			(at 0 -0.4191)
			(size 0.508 0.5334)
			(layers "F.Cu" "F.Mask" "F.Paste")
			(net "GND")
		)
		(pad "2" smd rect
			(at 0 0.4191)
			(size 0.508 0.5334)
			(layers "F.Cu" "F.Mask" "F.Paste")
			(net "VDD_7401_EN")
		)
		(zone
			(layer "F.Cu")
			(hatch none 0.5)
			(connect_pads
				(clearance 0)
			)
			(min_thickness 0.25)
			(keepout
				(tracks not_allowed)
				(vias allowed)
				(pads allowed)
				(copperpour not_allowed)
				(footprints allowed)
			)
			(placement
				(enabled no)
				(sheetname "")
			)
			(fill
				(thermal_gap 0.5)
				(thermal_bridge_width 0.5)
				(island_removal_mode 0)
			)
			(polygon
				(pts
					(xy 0.6604 34.1376) (xy 0.6604 34.1884) (xy 0.6096 34.1884) (xy 0.6096 34.1376)
				)
			)
		)
	)
	(footprint ""
		(layer "F.Cu")
		(at 74.651006 14.256004)
		(property "Reference" "V_A-DQ16"
			(at 0 0 0)
			(layer "F.SilkS")
			(hide yes)
			(effects
				(font
					(size 1.27 1.27)
				)
			)
		)
		(property "Value" ""
			(at 0 0 0)
			(layer "F.Fab")
			(effects
				(font
					(size 1.27 1.27)
				)
			)
		)
		(duplicate_pad_numbers_are_jumpers no)
		(pad "1" thru_hole circle
			(at 0 0)
			(size 0.762 0.762)
			(drill 0.20574)
			(layers "*.Cu" "*.Mask")
			(remove_unused_layers no)
			(net "DDR0_32A_DQ16")
			(clearance 0.127)
			(thermal_gap 0.127)
			(padstack
				(mode front_inner_back)
				(layer "Inner"
					(shape circle)
					(size 0.4572 0.4572)
					(clearance 0.1143)
				)
				(layer "B.Cu"
					(shape circle)
					(size 0.4572 0.4572)
					(clearance 0.1143)
				)
			)
		)
	)
	(footprint ""
		(layer "F.Cu")
		(at 75.438 23.495 -90)
		(property "Reference" "R364"
			(at 0 0 270)
			(layer "F.SilkS")
			(hide yes)
			(effects
				(font
					(size 1.27 1.27)
				)
			)
		)
		(property "Value" "100"
			(at -0.148158 1.3462 0)
			(unlocked yes)
			(layer "F.Fab")
			(hide yes)
			(effects
				(font
					(size 1.27 0.9652)
					(thickness 0.000001)
				)
				(justify left)
			)
		)
		(property "Device Type" "REST4030"
			(at -0.148158 1.3462 0)
			(unlocked yes)
			(layer "F.Fab")
			(hide yes)
			(effects
				(font
					(size 1.27 0.9652)
					(thickness 0.000001)
				)
				(justify left)
			)
		)
		(duplicate_pad_numbers_are_jumpers no)
		(fp_poly
			(pts
				(xy 0.635 1.0668) (xy 0.635 -1.0668) (xy -0.635 -1.0668) (xy -0.635 1.0668)
			)
			(stroke
				(width 0)
				(type default)
			)
			(fill no)
			(layer "F.CrtYd")
		)
		(fp_line
			(start -0.254 0.508)
			(end -0.254 -0.508)
			(stroke
				(width 0.0254)
				(type default)
			)
			(layer "F.Fab")
		)
		(fp_line
			(start 0.254 0.508)
			(end -0.254 0.508)
			(stroke
				(width 0.0254)
				(type default)
			)
			(layer "F.Fab")
		)
		(fp_line
			(start -0.254 -0.508)
			(end 0.254 -0.508)
			(stroke
				(width 0.0254)
				(type default)
			)
			(layer "F.Fab")
		)
		(fp_line
			(start 0.254 -0.508)
			(end 0.254 0.508)
			(stroke
				(width 0.0254)
				(type default)
			)
			(layer "F.Fab")
		)
		(pad "1" smd rect
			(at 0 -0.4191 270)
			(size 0.508 0.5334)
			(layers "F.Cu" "F.Mask" "F.Paste")
			(net "DDR0_32A_VREF1B")
		)
		(pad "2" smd rect
			(at 0 0.4191 270)
			(size 0.508 0.5334)
			(layers "F.Cu" "F.Mask" "F.Paste")
			(net "DDR_VDDQ")
		)
		(zone
			(layer "F.Cu")
			(hatch none 0.5)
			(connect_pads
				(clearance 0)
			)
			(min_thickness 0.25)
			(keepout
				(tracks not_allowed)
				(vias allowed)
				(pads allowed)
				(copperpour not_allowed)
				(footprints allowed)
			)
			(placement
				(enabled no)
				(sheetname "")
			)
			(fill
				(thermal_gap 0.5)
				(thermal_bridge_width 0.5)
				(island_removal_mode 0)
			)
			(polygon
				(pts
					(xy 75.4634 23.5204) (xy 75.4126 23.5204) (xy 75.4126 23.4696) (xy 75.4634 23.4696)
				)
			)
		)
	)
	(footprint ""
		(layer "F.Cu")
		(at 25.527 29.337 180)
		(property "Reference" "R60"
			(at -0.02667 0.889 90)
			(unlocked yes)
			(layer "F.SilkS")
			(effects
				(font
					(size 0.7874 0.5842)
					(thickness 0.127)
				)
				(justify left)
			)
		)
		(property "Value" "4.75K"
			(at -0.148158 1.3462 270)
			(unlocked yes)
			(layer "F.Fab")
			(hide yes)
			(effects
				(font
					(size 1.27 0.9652)
					(thickness 0.000001)
				)
				(justify left)
			)
		)
		(property "Device Type" "REST4024"
			(at -0.148158 1.3462 270)
			(unlocked yes)
			(layer "F.Fab")
			(hide yes)
			(effects
				(font
					(size 1.27 0.9652)
					(thickness 0.000001)
				)
				(justify left)
			)
		)
		(duplicate_pad_numbers_are_jumpers no)
		(fp_poly
			(pts
				(xy 0.635 1.0668) (xy 0.635 -1.0668) (xy -0.635 -1.0668) (xy -0.635 1.0668)
			)
			(stroke
				(width 0)
				(type default)
			)
			(fill no)
			(layer "F.CrtYd")
		)
		(fp_line
			(start 0.254 0.508)
			(end -0.254 0.508)
			(stroke
				(width 0.0254)
				(type default)
			)
			(layer "F.Fab")
		)
		(fp_line
			(start 0.254 -0.508)
			(end 0.254 0.508)
			(stroke
				(width 0.0254)
				(type default)
			)
			(layer "F.Fab")
		)
		(fp_line
			(start -0.254 0.508)
			(end -0.254 -0.508)
			(stroke
				(width 0.0254)
				(type default)
			)
			(layer "F.Fab")
		)
		(fp_line
			(start -0.254 -0.508)
			(end 0.254 -0.508)
			(stroke
				(width 0.0254)
				(type default)
			)
			(layer "F.Fab")
		)
		(pad "1" smd rect
			(at 0 -0.4191 180)
			(size 0.508 0.5334)
			(layers "F.Cu" "F.Mask" "F.Paste")
			(net "CPLD_PGRM_JTAG_SEL")
		)
		(pad "2" smd rect
			(at 0 0.4191 180)
			(size 0.508 0.5334)
			(layers "F.Cu" "F.Mask" "F.Paste")
			(net "GND")
		)
		(zone
			(layer "F.Cu")
			(hatch none 0.5)
			(connect_pads
				(clearance 0)
			)
			(min_thickness 0.25)
			(keepout
				(tracks not_allowed)
				(vias allowed)
				(pads allowed)
				(copperpour not_allowed)
				(footprints allowed)
			)
			(placement
				(enabled no)
				(sheetname "")
			)
			(fill
				(thermal_gap 0.5)
				(thermal_bridge_width 0.5)
				(island_removal_mode 0)
			)
			(polygon
				(pts
					(xy 25.5016 29.3624) (xy 25.5016 29.3116) (xy 25.5524 29.3116) (xy 25.5524 29.3624)
				)
			)
		)
	)
	(footprint ""
		(layer "F.Cu")
		(at 36.2712 42.545 90)
		(property "Reference" "R111"
			(at 0 0 90)
			(layer "F.SilkS")
			(hide yes)
			(effects
				(font
					(size 1.27 1.27)
				)
			)
		)
		(property "Value" "10"
			(at -0.148158 1.3462 180)
			(unlocked yes)
			(layer "F.Fab")
			(hide yes)
			(effects
				(font
					(size 1.27 0.9652)
					(thickness 0.000001)
				)
				(justify left)
			)
		)
		(property "Device Type" "REST0076"
			(at -0.148158 1.3462 180)
			(unlocked yes)
			(layer "F.Fab")
			(hide yes)
			(effects
				(font
					(size 1.27 0.9652)
					(thickness 0.000001)
				)
				(justify left)
			)
		)
		(duplicate_pad_numbers_are_jumpers no)
		(fp_poly
			(pts
				(xy 0.635 1.0668) (xy 0.635 -1.0668) (xy -0.635 -1.0668) (xy -0.635 1.0668)
			)
			(stroke
				(width 0)
				(type default)
			)
			(fill no)
			(layer "F.CrtYd")
		)
		(fp_line
			(start 0.254 -0.508)
			(end 0.254 0.508)
			(stroke
				(width 0.0254)
				(type default)
			)
			(layer "F.Fab")
		)
		(fp_line
			(start -0.254 -0.508)
			(end 0.254 -0.508)
			(stroke
				(width 0.0254)
				(type default)
			)
			(layer "F.Fab")
		)
		(fp_line
			(start 0.254 0.508)
			(end -0.254 0.508)
			(stroke
				(width 0.0254)
				(type default)
			)
			(layer "F.Fab")
		)
		(fp_line
			(start -0.254 0.508)
			(end -0.254 -0.508)
			(stroke
				(width 0.0254)
				(type default)
			)
			(layer "F.Fab")
		)
		(pad "1" smd rect
			(at 0 -0.4191 90)
			(size 0.508 0.5334)
			(layers "F.Cu" "F.Mask" "F.Paste")
			(net "10N2410")
		)
		(pad "2" smd rect
			(at 0 0.4191 90)
			(size 0.508 0.5334)
			(layers "F.Cu" "F.Mask" "F.Paste")
			(net "NFP_VDD_CORE_ISEN2_N")
		)
		(zone
			(layer "F.Cu")
			(hatch none 0.5)
			(connect_pads
				(clearance 0)
			)
			(min_thickness 0.25)
			(keepout
				(tracks not_allowed)
				(vias allowed)
				(pads allowed)
				(copperpour not_allowed)
				(footprints allowed)
			)
			(placement
				(enabled no)
				(sheetname "")
			)
			(fill
				(thermal_gap 0.5)
				(thermal_bridge_width 0.5)
				(island_removal_mode 0)
			)
			(polygon
				(pts
					(xy 36.2458 42.5196) (xy 36.2966 42.5196) (xy 36.2966 42.5704) (xy 36.2458 42.5704)
				)
			)
		)
	)
)
